# T6G (Grand Teton) — schematic netlist excerpt (pin names and nets, part order shuffled) for the footprints in the layout excerpt that follows; sources: Cadence DE-HDL packaged netlist, KiCad conversion of 04192023_DAF0TMB3IC0_F0TG_MB_C_brd_V02_OCP.brd

PC439_2  Q_CAP  0.1UF 25V 10% X7R  pkg 0402  page 222 : A = SW_P12V_AUX_PVDDIO_P1_FLT ; B = GND
R933  Q_RES  33 5% CHIP  pkg 0402LF  page 81 : A = FM_SMERR_LED_R_N ; B = FM_SMERR_LED_N

(kicad_pcb
	(version 20260206)
	(generator "pcbnew")
	(generator_version "10.0")
	(general
		(thickness 1.6)
		(legacy_teardrops no)
	)
	(paper "A4")
	(title_block
		(title "04192023_DAF0TMB3IC0_F0TG_MB_C_brd_V02_OCP.brd")
		(comment 1 "Grand Teton / footprints 2330-2331 of 8354")
	)
	(layers
		(0 "F.Cu" signal "TOP")
		(4 "In1.Cu" signal "GND")
		(6 "In2.Cu" signal "IN1")
		(8 "In3.Cu" signal "GND1")
		(10 "In4.Cu" signal "IN2")
		(12 "In5.Cu" signal "GND2")
		(14 "In6.Cu" signal "IN3")
		(16 "In7.Cu" signal "GND3")
		(18 "In8.Cu" signal "VCC")
		(20 "In9.Cu" signal "VCC1")
		(22 "In10.Cu" signal "GND4")
		(24 "In11.Cu" signal "IN4")
		(26 "In12.Cu" signal "GND5")
		(28 "In13.Cu" signal "IN5")
		(30 "In14.Cu" signal "GND6")
		(32 "In15.Cu" signal "IN6")
		(34 "In16.Cu" signal "GND7")
		(2 "B.Cu" signal "BOTTOM")
		(9 "F.Adhes" user "F.Adhesive")
		(11 "B.Adhes" user "B.Adhesive")
		(13 "F.Paste" user "Package Geometry/Pastemask Top")
		(15 "B.Paste" user "Package Geometry/Pastemask Bottom")
		(5 "F.SilkS" user "Ref Des/Silkscreen Top")
		(7 "B.SilkS" user "Ref Des/Silkscreen Bottom")
		(1 "F.Mask" user "Board Geometry/Soldermask Top")
		(3 "B.Mask" user "Board Geometry/Soldermask Bottom")
		(17 "Dwgs.User" user "User.Drawings")
		(19 "Cmts.User" user "User.Comments")
		(21 "Eco1.User" user "User.Eco1")
		(23 "Eco2.User" user "User.Eco2")
		(25 "Edge.Cuts" user "Board Geometry/Outline")
		(27 "Margin" user)
		(31 "F.CrtYd" user "Package Geometry/Place Bound Top")
		(29 "B.CrtYd" user "Package Geometry/Place Bound Bottom")
		(35 "F.Fab" user "Ref Des/Assembly Top")
		(33 "B.Fab" user "Ref Des/Assembly Bottom")
	)
	(footprint ""
		(layer "F.Cu")
		(at 185.039 -129.377948 90)
		(property "Reference" "R933"
			(at 0 0 90)
			(layer "F.SilkS")
			(hide yes)
			(effects
				(font
					(size 1.27 1.27)
				)
			)
		)
		(property "Value" ""
			(at 0 0 90)
			(layer "F.Fab")
			(effects
				(font
					(size 1.27 1.27)
				)
			)
		)
		(duplicate_pad_numbers_are_jumpers no)
		(fp_line
			(start 0.7874 -0.4064)
			(end 0.7874 0.4064)
			(stroke
				(width 0.1524)
				(type default)
			)
			(layer "F.SilkS")
		)
		(fp_line
			(start -0.7874 -0.4064)
			(end 0.7874 -0.4064)
			(stroke
				(width 0.1524)
				(type default)
			)
			(layer "F.SilkS")
		)
		(fp_line
			(start 0.7874 0.4064)
			(end -0.7874 0.4064)
			(stroke
				(width 0.1524)
				(type default)
			)
			(layer "F.SilkS")
		)
		(fp_line
			(start -0.7874 0.4064)
			(end -0.7874 -0.4064)
			(stroke
				(width 0.1524)
				(type default)
			)
			(layer "F.SilkS")
		)
		(fp_line
			(start -0.12065 -0.305054)
			(end -0.12065 -0.2794)
			(stroke
				(width 0.1)
				(type default)
			)
			(layer "F.Fab")
		)
		(fp_line
			(start -0.67945 -0.305054)
			(end -0.12065 -0.305054)
			(stroke
				(width 0.1)
				(type default)
			)
			(layer "F.Fab")
		)
		(fp_line
			(start 0.67945 -0.3048)
			(end 0.67945 0.3048)
			(stroke
				(width 0.1)
				(type default)
			)
			(layer "F.Fab")
		)
		(fp_line
			(start 0.12065 -0.3048)
			(end 0.67945 -0.3048)
			(stroke
				(width 0.1)
				(type default)
			)
			(layer "F.Fab")
		)
		(fp_line
			(start 0.12065 -0.2794)
			(end 0.12065 -0.3048)
			(stroke
				(width 0.1)
				(type default)
			)
			(layer "F.Fab")
		)
		(fp_line
			(start -0.12065 -0.2794)
			(end 0.12065 -0.2794)
			(stroke
				(width 0.1)
				(type default)
			)
			(layer "F.Fab")
		)
		(fp_line
			(start 0.120396 0.2794)
			(end -0.12065 0.2794)
			(stroke
				(width 0.1)
				(type default)
			)
			(layer "F.Fab")
		)
		(fp_line
			(start -0.12065 0.2794)
			(end -0.12065 0.3048)
			(stroke
				(width 0.1)
				(type default)
			)
			(layer "F.Fab")
		)
		(fp_line
			(start 0.67945 0.3048)
			(end 0.120396 0.3048)
			(stroke
				(width 0.1)
				(type default)
			)
			(layer "F.Fab")
		)
		(fp_line
			(start 0.120396 0.3048)
			(end 0.120396 0.2794)
			(stroke
				(width 0.1)
				(type default)
			)
			(layer "F.Fab")
		)
		(fp_line
			(start -0.12065 0.3048)
			(end -0.67945 0.3048)
			(stroke
				(width 0.1)
				(type default)
			)
			(layer "F.Fab")
		)
		(fp_line
			(start -0.67945 0.3048)
			(end -0.67945 -0.305054)
			(stroke
				(width 0.1)
				(type default)
			)
			(layer "F.Fab")
		)
		(pad "1" smd circle
			(at -0.40005 0 90)
			(size 0 0)
			(layers "F.Cu" "F.Mask" "F.Paste")
			(net "FM_SMERR_LED_R_N")
		)
		(pad "2" smd circle
			(at 0.40005 0 90)
			(size 0 0)
			(layers "F.Cu" "F.Mask" "F.Paste")
			(net "FM_SMERR_LED_N")
		)
	)
	(footprint ""
		(layer "F.Cu")
		(at 41.050718 -351.10547)
		(property "Reference" "PC439_2"
			(at 0 0 0)
			(layer "F.SilkS")
			(hide yes)
			(effects
				(font
					(size 1.27 1.27)
				)
			)
		)
		(property "Value" ""
			(at 0 0 0)
			(layer "F.Fab")
			(effects
				(font
					(size 1.27 1.27)
				)
			)
		)
		(duplicate_pad_numbers_are_jumpers no)
		(fp_line
			(start -0.7874 -0.4064)
			(end 0.7874 -0.4064)
			(stroke
				(width 0.1524)
				(type default)
			)
			(layer "F.SilkS")
		)
		(fp_line
			(start -0.7874 0.4064)
			(end -0.7874 -0.4064)
			(stroke
				(width 0.1524)
				(type default)
			)
			(layer "F.SilkS")
		)
		(fp_line
			(start 0.7874 -0.4064)
			(end 0.7874 0.4064)
			(stroke
				(width 0.1524)
				(type default)
			)
			(layer "F.SilkS")
		)
		(fp_line
			(start 0.7874 0.4064)
			(end -0.7874 0.4064)
			(stroke
				(width 0.1524)
				(type default)
			)
			(layer "F.SilkS")
		)
		(fp_line
			(start -0.67945 -0.305054)
			(end -0.12065 -0.305054)
			(stroke
				(width 0.1)
				(type default)
			)
			(layer "F.Fab")
		)
		(fp_line
			(start -0.67945 0.3048)
			(end -0.67945 -0.305054)
			(stroke
				(width 0.1)
				(type default)
			)
			(layer "F.Fab")
		)
		(fp_line
			(start -0.12065 -0.305054)
			(end -0.12065 -0.2794)
			(stroke
				(width 0.1)
				(type default)
			)
			(layer "F.Fab")
		)
		(fp_line
			(start -0.12065 -0.2794)
			(end 0.12065 -0.2794)
			(stroke
				(width 0.1)
				(type default)
			)
			(layer "F.Fab")
		)
		(fp_line
			(start -0.12065 0.2794)
			(end -0.12065 0.3048)
			(stroke
				(width 0.1)
				(type default)
			)
			(layer "F.Fab")
		)
		(fp_line
			(start -0.12065 0.3048)
			(end -0.67945 0.3048)
			(stroke
				(width 0.1)
				(type default)
			)
			(layer "F.Fab")
		)
		(fp_line
			(start 0.120396 0.2794)
			(end -0.12065 0.2794)
			(stroke
				(width 0.1)
				(type default)
			)
			(layer "F.Fab")
		)
		(fp_line
			(start 0.120396 0.3048)
			(end 0.120396 0.2794)
			(stroke
				(width 0.1)
				(type default)
			)
			(layer "F.Fab")
		)
		(fp_line
			(start 0.12065 -0.3048)
			(end 0.67945 -0.3048)
			(stroke
				(width 0.1)
				(type default)
			)
			(layer "F.Fab")
		)
		(fp_line
			(start 0.12065 -0.2794)
			(end 0.12065 -0.3048)
			(stroke
				(width 0.1)
				(type default)
			)
			(layer "F.Fab")
		)
		(fp_line
			(start 0.67945 -0.3048)
			(end 0.67945 0.3048)
			(stroke
				(width 0.1)
				(type default)
			)
			(layer "F.Fab")
		)
		(fp_line
			(start 0.67945 0.3048)
			(end 0.120396 0.3048)
			(stroke
				(width 0.1)
				(type default)
			)
			(layer "F.Fab")
		)
		(pad "1" smd circle
			(at -0.40005 0)
			(size 0 0)
			(layers "F.Cu" "F.Mask" "F.Paste")
			(net "SW_P12V_AUX_PVDDIO_P1_FLT")
		)
		(pad "2" smd circle
			(at 0.40005 0)
			(size 0 0)
			(layers "F.Cu" "F.Mask" "F.Paste")
			(net "GND")
		)
	)
)
